(kicad_pcb
	(version 20260206)
	(generator "pcbnew")
	(generator_version "10.0")
	(general
		(thickness 1.6)
		(legacy_teardrops no)
	)
	(paper "A4")
	(title_block
		(title "panther-plus-userver — 13130-1b_20150205.brd")
		(comment 1 "Honey Badger (Wiwynn) / footprint 406 of 1509 (DIMM2), pads 9-15 of 210")
	)
	(layers
		(0 "F.Cu" signal "TOP")
		(4 "In1.Cu" signal "L2")
		(6 "In2.Cu" signal "L3")
		(8 "In3.Cu" signal "L4")
		(10 "In4.Cu" signal "L5")
		(12 "In5.Cu" signal "L6")
		(14 "In6.Cu" signal "L7")
		(16 "In7.Cu" signal "L8")
		(18 "In8.Cu" signal "L9")
		(20 "In9.Cu" signal "L10")
		(22 "In10.Cu" signal "L11")
		(2 "B.Cu" signal "BOTTOM")
		(9 "F.Adhes" user "F.Adhesive")
		(11 "B.Adhes" user "B.Adhesive")
		(13 "F.Paste" user "Package Geometry/Pastemask Top")
		(15 "B.Paste" user "Package Geometry/Pastemask Bottom")
		(5 "F.SilkS" user "Ref Des/Silkscreen Top")
		(7 "B.SilkS" user "Ref Des/Silkscreen Bottom")
		(1 "F.Mask" user "Board Geometry/Soldermask Top")
		(3 "B.Mask" user "Board Geometry/Soldermask Bottom")
		(17 "Dwgs.User" user "User.Drawings")
		(19 "Cmts.User" user "User.Comments")
		(21 "Eco1.User" user "User.Eco1")
		(23 "Eco2.User" user "User.Eco2")
		(25 "Edge.Cuts" user "Board Geometry/Outline")
		(27 "Margin" user)
		(31 "F.CrtYd" user "Package Geometry/Place Bound Top")
		(29 "B.CrtYd" user "Package Geometry/Place Bound Bottom")
		(35 "F.Fab" user "Ref Des/Assembly Top")
		(33 "B.Fab" user "Ref Des/Assembly Bottom")
	)
	(footprint ""
		(layer "F.Cu")
		(at 158.500064 -66.699892 180)
		(property "Reference" "DIMM2"
			(at 0 0 180)
			(layer "F.SilkS")
			(hide yes)
			(effects
				(font
					(size 1.27 1.27)
				)
			)
		)
		(property "Value" "DDR3-204P-174-COLAY-1-GP"
			(at -40.682164 -17.468088 180)
			(unlocked yes)
			(layer "F.Fab")
			(hide yes)
			(effects
				(font
					(size 1.016 1.016)
					(thickness 0.1524)
				)
			)
		)
		(property "Device Type" "AS0A626-H8SN-7H-COLAY-1"
			(at -40.682164 -18.992088 180)
			(unlocked yes)
			(layer "F.Fab")
			(hide yes)
			(effects
				(font
					(size 1.016 1.016)
					(thickness 0.1524)
				)
			)
		)
		(duplicate_pad_numbers_are_jumpers no)
		(pad "7" smd custom
			(at -29.85008 4.106672 180)
			(size 0.1143 0.1143)
			(layers "F.Cu" "F.Mask" "F.Paste")
			(net "M_A_DQ5")
			(options
				(clearance outline)
				(anchor circle)
			)
			(primitives
				(gr_poly
					(pts
						(xy 0 0.9017) (xy -0.03175 0.89916) (xy -0.0635 0.889) (xy -0.09144 0.87376) (xy -0.11684 0.85344)
						(xy -0.13716 0.82804) (xy -0.1524 0.8001) (xy -0.16256 0.76835) (xy -0.1651 0.7366) (xy -0.1651 0.11938)
						(xy -0.17272 0.11176) (xy -0.19812 0.0762) (xy -0.2032 0.06604) (xy -0.20701 0.05715) (xy -0.21209 0.04699)
						(xy -0.2159 0.03683) (xy -0.21844 0.02667) (xy -0.22225 0.01524) (xy -0.22352 0.00508) (xy -0.22606 -0.00508)
						(xy -0.22733 -0.01651) (xy -0.22733 -0.02667) (xy -0.2286 -0.0381) (xy -0.22733 -0.04953) (xy -0.22733 -0.05969)
						(xy -0.22606 -0.07112) (xy -0.22352 -0.08128) (xy -0.22225 -0.09144) (xy -0.21844 -0.10287) (xy -0.2159 -0.11303)
						(xy -0.21209 -0.12319) (xy -0.20701 -0.13335) (xy -0.2032 -0.14224) (xy -0.19812 -0.1524) (xy -0.17272 -0.18796)
						(xy -0.1651 -0.19558) (xy -0.1651 -0.7366) (xy -0.16256 -0.76835) (xy -0.1524 -0.8001) (xy -0.13716 -0.82804)
						(xy -0.11684 -0.85344) (xy -0.09144 -0.87376) (xy -0.0635 -0.889) (xy -0.03175 -0.89916) (xy 0 -0.9017)
						(xy 0.03175 -0.89916) (xy 0.0635 -0.889) (xy 0.09144 -0.87376) (xy 0.11684 -0.85344) (xy 0.13716 -0.82804)
						(xy 0.1524 -0.8001) (xy 0.16256 -0.76835) (xy 0.1651 -0.7366) (xy 0.1651 -0.19685) (xy 0.17272 -0.18923)
						(xy 0.17907 -0.18034) (xy 0.18669 -0.17145) (xy 0.19177 -0.16256) (xy 0.19812 -0.15367) (xy 0.20828 -0.13335)
						(xy 0.21971 -0.10287) (xy 0.22225 -0.09271) (xy 0.22479 -0.08128) (xy 0.22606 -0.07112) (xy 0.2286 -0.05969)
						(xy 0.2286 -0.01651) (xy 0.22606 -0.00508) (xy 0.22479 0.00508) (xy 0.22225 0.01651) (xy 0.21971 0.02667)
						(xy 0.20828 0.05715) (xy 0.19812 0.07747) (xy 0.19177 0.08636) (xy 0.18669 0.09525) (xy 0.17907 0.10414)
						(xy 0.17272 0.11303) (xy 0.1651 0.12065) (xy 0.1651 0.7366) (xy 0.16256 0.76835) (xy 0.1524 0.8001)
						(xy 0.13716 0.82804) (xy 0.11684 0.85344) (xy 0.09144 0.87376) (xy 0.0635 0.889) (xy 0.03175 0.89916)
					)
					(width 0)
					(fill yes)
				)
			)
		)
		(pad "8" smd custom
			(at -29.550106 -4.106672 180)
			(size 0.1143 0.1143)
			(layers "F.Cu" "F.Mask" "F.Paste")
			(net "GND")
			(options
				(clearance outline)
				(anchor circle)
			)
			(primitives
				(gr_poly
					(pts
						(xy 0 0.9017) (xy -0.03175 0.89916) (xy -0.0635 0.889) (xy -0.09144 0.87376) (xy -0.11684 0.85344)
						(xy -0.13716 0.82804) (xy -0.1524 0.8001) (xy -0.16256 0.76835) (xy -0.1651 0.7366) (xy -0.1651 0.19685)
						(xy -0.17272 0.18923) (xy -0.17907 0.18034) (xy -0.18669 0.17145) (xy -0.19177 0.16256) (xy -0.19812 0.15367)
						(xy -0.20828 0.13335) (xy -0.21971 0.10287) (xy -0.22225 0.09271) (xy -0.22479 0.08128) (xy -0.22606 0.07112)
						(xy -0.2286 0.05969) (xy -0.2286 0.01651) (xy -0.22606 0.00508) (xy -0.22479 -0.00508) (xy -0.22225 -0.01651)
						(xy -0.21971 -0.02667) (xy -0.20828 -0.05715) (xy -0.19812 -0.07747) (xy -0.19177 -0.08636) (xy -0.18669 -0.09525)
						(xy -0.17907 -0.10414) (xy -0.17272 -0.11303) (xy -0.1651 -0.12065) (xy -0.1651 -0.7366) (xy -0.16256 -0.76835)
						(xy -0.1524 -0.8001) (xy -0.13716 -0.82804) (xy -0.11684 -0.85344) (xy -0.09144 -0.87376) (xy -0.0635 -0.889)
						(xy -0.03175 -0.89916) (xy 0 -0.9017) (xy 0.03175 -0.89916) (xy 0.0635 -0.889) (xy 0.09144 -0.87376)
						(xy 0.11684 -0.85344) (xy 0.13716 -0.82804) (xy 0.1524 -0.8001) (xy 0.16256 -0.76835) (xy 0.1651 -0.7366)
						(xy 0.1651 -0.11938) (xy 0.17272 -0.11176) (xy 0.19812 -0.0762) (xy 0.2032 -0.06604) (xy 0.20701 -0.05715)
						(xy 0.21209 -0.04699) (xy 0.2159 -0.03683) (xy 0.21844 -0.02667) (xy 0.22225 -0.01524) (xy 0.22352 -0.00508)
						(xy 0.22606 0.00508) (xy 0.22733 0.01651) (xy 0.22733 0.02667) (xy 0.2286 0.0381) (xy 0.22733 0.04953)
						(xy 0.22733 0.05969) (xy 0.22606 0.07112) (xy 0.22352 0.08128) (xy 0.22225 0.09144) (xy 0.21844 0.10287)
						(xy 0.2159 0.11303) (xy 0.21209 0.12319) (xy 0.20701 0.13335) (xy 0.2032 0.14224) (xy 0.19812 0.1524)
						(xy 0.17272 0.18796) (xy 0.1651 0.19558) (xy 0.1651 0.7366) (xy 0.16256 0.76835) (xy 0.1524 0.8001)
						(xy 0.13716 0.82804) (xy 0.11684 0.85344) (xy 0.09144 0.87376) (xy 0.0635 0.889) (xy 0.03175 0.89916)
					)
					(width 0)
					(fill yes)
				)
			)
		)
		(pad "9" smd custom
			(at -29.249878 4.106672 180)
			(size 0.1143 0.1143)
			(layers "F.Cu" "F.Mask" "F.Paste")
			(net "GND")
			(options
				(clearance outline)
				(anchor circle)
			)
			(primitives
				(gr_poly
					(pts
						(xy 0 0.9017) (xy -0.03175 0.89916) (xy -0.0635 0.889) (xy -0.09144 0.87376) (xy -0.11684 0.85344)
						(xy -0.13716 0.82804) (xy -0.1524 0.8001) (xy -0.16256 0.76835) (xy -0.1651 0.7366) (xy -0.1651 -0.13462)
						(xy -0.17272 -0.14224) (xy -0.19812 -0.1778) (xy -0.2032 -0.18796) (xy -0.20701 -0.19685) (xy -0.21209 -0.20701)
						(xy -0.2159 -0.21717) (xy -0.21844 -0.22733) (xy -0.22225 -0.23876) (xy -0.22352 -0.24892) (xy -0.22606 -0.25908)
						(xy -0.22733 -0.27051) (xy -0.22733 -0.28067) (xy -0.2286 -0.2921) (xy -0.22733 -0.30353) (xy -0.22733 -0.31369)
						(xy -0.22606 -0.32512) (xy -0.22352 -0.33528) (xy -0.22225 -0.34544) (xy -0.21844 -0.35687) (xy -0.2159 -0.36703)
						(xy -0.21209 -0.37719) (xy -0.20701 -0.38735) (xy -0.2032 -0.39624) (xy -0.19812 -0.4064) (xy -0.17272 -0.44196)
						(xy -0.1651 -0.44958) (xy -0.1651 -0.7366) (xy -0.16256 -0.76835) (xy -0.1524 -0.8001) (xy -0.13716 -0.82804)
						(xy -0.11684 -0.85344) (xy -0.09144 -0.87376) (xy -0.0635 -0.889) (xy -0.03175 -0.89916) (xy 0 -0.9017)
						(xy 0.03175 -0.89916) (xy 0.0635 -0.889) (xy 0.09144 -0.87376) (xy 0.11684 -0.85344) (xy 0.13716 -0.82804)
						(xy 0.1524 -0.8001) (xy 0.16256 -0.76835) (xy 0.1651 -0.7366) (xy 0.1651 -0.44958) (xy 0.17272 -0.44196)
						(xy 0.19812 -0.4064) (xy 0.2032 -0.39624) (xy 0.20701 -0.38735) (xy 0.21209 -0.37719) (xy 0.2159 -0.36703)
						(xy 0.21844 -0.35687) (xy 0.22225 -0.34544) (xy 0.22352 -0.33528) (xy 0.22606 -0.32512) (xy 0.22733 -0.31369)
						(xy 0.22733 -0.30353) (xy 0.2286 -0.2921) (xy 0.22733 -0.28067) (xy 0.22733 -0.27051) (xy 0.22606 -0.25908)
						(xy 0.22352 -0.24892) (xy 0.22225 -0.23876) (xy 0.21844 -0.22733) (xy 0.2159 -0.21717) (xy 0.21209 -0.20701)
						(xy 0.20701 -0.19685) (xy 0.2032 -0.18796) (xy 0.19812 -0.1778) (xy 0.17272 -0.14224) (xy 0.1651 -0.13462)
						(xy 0.1651 0.7366) (xy 0.16256 0.76835) (xy 0.1524 0.8001) (xy 0.13716 0.82804) (xy 0.11684 0.85344)
						(xy 0.09144 0.87376) (xy 0.0635 0.889) (xy 0.03175 0.89916)
					)
					(width 0)
					(fill yes)
				)
			)
		)
		(pad "10" smd custom
			(at -28.949904 -4.106672 180)
			(size 0.1143 0.1143)
			(layers "F.Cu" "F.Mask" "F.Paste")
			(net "M_A_DQS_DN0")
			(options
				(clearance outline)
				(anchor circle)
			)
			(primitives
				(gr_poly
					(pts
						(xy 0 0.9017) (xy -0.03175 0.89916) (xy -0.0635 0.889) (xy -0.09144 0.87376) (xy -0.11684 0.85344)
						(xy -0.13716 0.82804) (xy -0.1524 0.8001) (xy -0.16256 0.76835) (xy -0.1651 0.7366) (xy -0.1651 0.44958)
						(xy -0.17272 0.44196) (xy -0.19812 0.4064) (xy -0.2032 0.39624) (xy -0.20701 0.38735) (xy -0.21209 0.37719)
						(xy -0.2159 0.36703) (xy -0.21844 0.35687) (xy -0.22225 0.34544) (xy -0.22352 0.33528) (xy -0.22606 0.32512)
						(xy -0.22733 0.31369) (xy -0.22733 0.30353) (xy -0.2286 0.2921) (xy -0.22733 0.28067) (xy -0.22733 0.27051)
						(xy -0.22606 0.25908) (xy -0.22352 0.24892) (xy -0.22225 0.23876) (xy -0.21844 0.22733) (xy -0.2159 0.21717)
						(xy -0.21209 0.20701) (xy -0.20701 0.19685) (xy -0.2032 0.18796) (xy -0.19812 0.1778) (xy -0.17272 0.14224)
						(xy -0.1651 0.13462) (xy -0.1651 -0.7366) (xy -0.16256 -0.76835) (xy -0.1524 -0.8001) (xy -0.13716 -0.82804)
						(xy -0.11684 -0.85344) (xy -0.09144 -0.87376) (xy -0.0635 -0.889) (xy -0.03175 -0.89916) (xy 0 -0.9017)
						(xy 0.03175 -0.89916) (xy 0.0635 -0.889) (xy 0.09144 -0.87376) (xy 0.11684 -0.85344) (xy 0.13716 -0.82804)
						(xy 0.1524 -0.8001) (xy 0.16256 -0.76835) (xy 0.1651 -0.7366) (xy 0.1651 0.13462) (xy 0.17272 0.14224)
						(xy 0.19812 0.1778) (xy 0.2032 0.18796) (xy 0.20701 0.19685) (xy 0.21209 0.20701) (xy 0.2159 0.21717)
						(xy 0.21844 0.22733) (xy 0.22225 0.23876) (xy 0.22352 0.24892) (xy 0.22606 0.25908) (xy 0.22733 0.27051)
						(xy 0.22733 0.28067) (xy 0.2286 0.2921) (xy 0.22733 0.30353) (xy 0.22733 0.31369) (xy 0.22606 0.32512)
						(xy 0.22352 0.33528) (xy 0.22225 0.34544) (xy 0.21844 0.35687) (xy 0.2159 0.36703) (xy 0.21209 0.37719)
						(xy 0.20701 0.38735) (xy 0.2032 0.39624) (xy 0.19812 0.4064) (xy 0.17272 0.44196) (xy 0.1651 0.44958)
						(xy 0.1651 0.7366) (xy 0.16256 0.76835) (xy 0.1524 0.8001) (xy 0.13716 0.82804) (xy 0.11684 0.85344)
						(xy 0.09144 0.87376) (xy 0.0635 0.889) (xy 0.03175 0.89916)
					)
					(width 0)
					(fill yes)
				)
			)
		)
		(pad "11" smd custom
			(at -28.64993 4.106672 180)
			(size 0.1143 0.1143)
			(layers "F.Cu" "F.Mask" "F.Paste")
			(net "GND")
			(options
				(clearance outline)
				(anchor circle)
			)
			(primitives
				(gr_poly
					(pts
						(xy 0 0.9017) (xy -0.03175 0.89916) (xy -0.0635 0.889) (xy -0.09144 0.87376) (xy -0.11684 0.85344)
						(xy -0.13716 0.82804) (xy -0.1524 0.8001) (xy -0.16256 0.76835) (xy -0.1651 0.7366) (xy -0.1651 0.11938)
						(xy -0.17272 0.11176) (xy -0.19812 0.0762) (xy -0.2032 0.06604) (xy -0.20701 0.05715) (xy -0.21209 0.04699)
						(xy -0.2159 0.03683) (xy -0.21844 0.02667) (xy -0.22225 0.01524) (xy -0.22352 0.00508) (xy -0.22606 -0.00508)
						(xy -0.22733 -0.01651) (xy -0.22733 -0.02667) (xy -0.2286 -0.0381) (xy -0.22733 -0.04953) (xy -0.22733 -0.05969)
						(xy -0.22606 -0.07112) (xy -0.22352 -0.08128) (xy -0.22225 -0.09144) (xy -0.21844 -0.10287) (xy -0.2159 -0.11303)
						(xy -0.21209 -0.12319) (xy -0.20701 -0.13335) (xy -0.2032 -0.14224) (xy -0.19812 -0.1524) (xy -0.17272 -0.18796)
						(xy -0.1651 -0.19558) (xy -0.1651 -0.7366) (xy -0.16256 -0.76835) (xy -0.1524 -0.8001) (xy -0.13716 -0.82804)
						(xy -0.11684 -0.85344) (xy -0.09144 -0.87376) (xy -0.0635 -0.889) (xy -0.03175 -0.89916) (xy 0 -0.9017)
						(xy 0.03175 -0.89916) (xy 0.0635 -0.889) (xy 0.09144 -0.87376) (xy 0.11684 -0.85344) (xy 0.13716 -0.82804)
						(xy 0.1524 -0.8001) (xy 0.16256 -0.76835) (xy 0.1651 -0.7366) (xy 0.1651 -0.19685) (xy 0.17272 -0.18923)
						(xy 0.17907 -0.18034) (xy 0.18669 -0.17145) (xy 0.19177 -0.16256) (xy 0.19812 -0.15367) (xy 0.20828 -0.13335)
						(xy 0.21971 -0.10287) (xy 0.22225 -0.09271) (xy 0.22479 -0.08128) (xy 0.22606 -0.07112) (xy 0.2286 -0.05969)
						(xy 0.2286 -0.01651) (xy 0.22606 -0.00508) (xy 0.22479 0.00508) (xy 0.22225 0.01651) (xy 0.21971 0.02667)
						(xy 0.20828 0.05715) (xy 0.19812 0.07747) (xy 0.19177 0.08636) (xy 0.18669 0.09525) (xy 0.17907 0.10414)
						(xy 0.17272 0.11303) (xy 0.1651 0.12065) (xy 0.1651 0.7366) (xy 0.16256 0.76835) (xy 0.1524 0.8001)
						(xy 0.13716 0.82804) (xy 0.11684 0.85344) (xy 0.09144 0.87376) (xy 0.0635 0.889) (xy 0.03175 0.89916)
					)
					(width 0)
					(fill yes)
				)
			)
		)
		(pad "12" smd custom
			(at -28.349956 -4.106672 180)
			(size 0.1143 0.1143)
			(layers "F.Cu" "F.Mask" "F.Paste")
			(net "M_A_DQS_DP0")
			(options
				(clearance outline)
				(anchor circle)
			)
			(primitives
				(gr_poly
					(pts
						(xy 0 0.9017) (xy -0.03175 0.89916) (xy -0.0635 0.889) (xy -0.09144 0.87376) (xy -0.11684 0.85344)
						(xy -0.13716 0.82804) (xy -0.1524 0.8001) (xy -0.16256 0.76835) (xy -0.1651 0.7366) (xy -0.1651 0.19685)
						(xy -0.17272 0.18923) (xy -0.17907 0.18034) (xy -0.18669 0.17145) (xy -0.19177 0.16256) (xy -0.19812 0.15367)
						(xy -0.20828 0.13335) (xy -0.21971 0.10287) (xy -0.22225 0.09271) (xy -0.22479 0.08128) (xy -0.22606 0.07112)
						(xy -0.2286 0.05969) (xy -0.2286 0.01651) (xy -0.22606 0.00508) (xy -0.22479 -0.00508) (xy -0.22225 -0.01651)
						(xy -0.21971 -0.02667) (xy -0.20828 -0.05715) (xy -0.19812 -0.07747) (xy -0.19177 -0.08636) (xy -0.18669 -0.09525)
						(xy -0.17907 -0.10414) (xy -0.17272 -0.11303) (xy -0.1651 -0.12065) (xy -0.1651 -0.7366) (xy -0.16256 -0.76835)
						(xy -0.1524 -0.8001) (xy -0.13716 -0.82804) (xy -0.11684 -0.85344) (xy -0.09144 -0.87376) (xy -0.0635 -0.889)
						(xy -0.03175 -0.89916) (xy 0 -0.9017) (xy 0.03175 -0.89916) (xy 0.0635 -0.889) (xy 0.09144 -0.87376)
						(xy 0.11684 -0.85344) (xy 0.13716 -0.82804) (xy 0.1524 -0.8001) (xy 0.16256 -0.76835) (xy 0.1651 -0.7366)
						(xy 0.1651 -0.11938) (xy 0.17272 -0.11176) (xy 0.19812 -0.0762) (xy 0.2032 -0.06604) (xy 0.20701 -0.05715)
						(xy 0.21209 -0.04699) (xy 0.2159 -0.03683) (xy 0.21844 -0.02667) (xy 0.22225 -0.01524) (xy 0.22352 -0.00508)
						(xy 0.22606 0.00508) (xy 0.22733 0.01651) (xy 0.22733 0.02667) (xy 0.2286 0.0381) (xy 0.22733 0.04953)
						(xy 0.22733 0.05969) (xy 0.22606 0.07112) (xy 0.22352 0.08128) (xy 0.22225 0.09144) (xy 0.21844 0.10287)
						(xy 0.2159 0.11303) (xy 0.21209 0.12319) (xy 0.20701 0.13335) (xy 0.2032 0.14224) (xy 0.19812 0.1524)
						(xy 0.17272 0.18796) (xy 0.1651 0.19558) (xy 0.1651 0.7366) (xy 0.16256 0.76835) (xy 0.1524 0.8001)
						(xy 0.13716 0.82804) (xy 0.11684 0.85344) (xy 0.09144 0.87376) (xy 0.0635 0.889) (xy 0.03175 0.89916)
					)
					(width 0)
					(fill yes)
				)
			)
		)
		(pad "13" smd custom
			(at -28.049982 4.106672 180)
			(size 0.1143 0.1143)
			(layers "F.Cu" "F.Mask" "F.Paste")
			(net "M_A_DQ6")
			(options
				(clearance outline)
				(anchor circle)
			)
			(primitives
				(gr_poly
					(pts
						(xy 0 0.9017) (xy -0.03175 0.89916) (xy -0.0635 0.889) (xy -0.09144 0.87376) (xy -0.11684 0.85344)
						(xy -0.13716 0.82804) (xy -0.1524 0.8001) (xy -0.16256 0.76835) (xy -0.1651 0.7366) (xy -0.1651 -0.13462)
						(xy -0.17272 -0.14224) (xy -0.19812 -0.1778) (xy -0.2032 -0.18796) (xy -0.20701 -0.19685) (xy -0.21209 -0.20701)
						(xy -0.2159 -0.21717) (xy -0.21844 -0.22733) (xy -0.22225 -0.23876) (xy -0.22352 -0.24892) (xy -0.22606 -0.25908)
						(xy -0.22733 -0.27051) (xy -0.22733 -0.28067) (xy -0.2286 -0.2921) (xy -0.22733 -0.30353) (xy -0.22733 -0.31369)
						(xy -0.22606 -0.32512) (xy -0.22352 -0.33528) (xy -0.22225 -0.34544) (xy -0.21844 -0.35687) (xy -0.2159 -0.36703)
						(xy -0.21209 -0.37719) (xy -0.20701 -0.38735) (xy -0.2032 -0.39624) (xy -0.19812 -0.4064) (xy -0.17272 -0.44196)
						(xy -0.1651 -0.44958) (xy -0.1651 -0.7366) (xy -0.16256 -0.76835) (xy -0.1524 -0.8001) (xy -0.13716 -0.82804)
						(xy -0.11684 -0.85344) (xy -0.09144 -0.87376) (xy -0.0635 -0.889) (xy -0.03175 -0.89916) (xy 0 -0.9017)
						(xy 0.03175 -0.89916) (xy 0.0635 -0.889) (xy 0.09144 -0.87376) (xy 0.11684 -0.85344) (xy 0.13716 -0.82804)
						(xy 0.1524 -0.8001) (xy 0.16256 -0.76835) (xy 0.1651 -0.7366) (xy 0.1651 -0.44958) (xy 0.17272 -0.44196)
						(xy 0.19812 -0.4064) (xy 0.2032 -0.39624) (xy 0.20701 -0.38735) (xy 0.21209 -0.37719) (xy 0.2159 -0.36703)
						(xy 0.21844 -0.35687) (xy 0.22225 -0.34544) (xy 0.22352 -0.33528) (xy 0.22606 -0.32512) (xy 0.22733 -0.31369)
						(xy 0.22733 -0.30353) (xy 0.2286 -0.2921) (xy 0.22733 -0.28067) (xy 0.22733 -0.27051) (xy 0.22606 -0.25908)
						(xy 0.22352 -0.24892) (xy 0.22225 -0.23876) (xy 0.21844 -0.22733) (xy 0.2159 -0.21717) (xy 0.21209 -0.20701)
						(xy 0.20701 -0.19685) (xy 0.2032 -0.18796) (xy 0.19812 -0.1778) (xy 0.17272 -0.14224) (xy 0.1651 -0.13462)
						(xy 0.1651 0.7366) (xy 0.16256 0.76835) (xy 0.1524 0.8001) (xy 0.13716 0.82804) (xy 0.11684 0.85344)
						(xy 0.09144 0.87376) (xy 0.0635 0.889) (xy 0.03175 0.89916)
					)
					(width 0)
					(fill yes)
				)
			)
		)
	)
)
